(kicad_pcb
	(version 20260206)
	(generator "pcbnew")
	(generator_version "10.0")
	(general
		(thickness 1.6)
		(legacy_teardrops no)
	)
	(paper "A4")
	(title_block
		(title "Bryce Canyon_IOM_M2_16342-2_OCP.brd")
		(comment 1 "Bryce Canyon / footprints 498-504 of 1146")
	)
	(layers
		(0 "F.Cu" signal "TOP")
		(4 "In1.Cu" signal "L2GND")
		(6 "In2.Cu" signal "L3")
		(8 "In3.Cu" signal "L4VCC")
		(10 "In4.Cu" signal "L5VCC")
		(12 "In5.Cu" signal "L6")
		(14 "In6.Cu" signal "L7GND")
		(2 "B.Cu" signal "BOTTOM")
		(9 "F.Adhes" user "F.Adhesive")
		(11 "B.Adhes" user "B.Adhesive")
		(13 "F.Paste" user "Package Geometry/Pastemask Top")
		(15 "B.Paste" user "Package Geometry/Pastemask Bottom")
		(5 "F.SilkS" user "Ref Des/Silkscreen Top")
		(7 "B.SilkS" user "Ref Des/Silkscreen Bottom")
		(1 "F.Mask" user "Board Geometry/Soldermask Top")
		(3 "B.Mask" user "Board Geometry/Soldermask Bottom")
		(17 "Dwgs.User" user "User.Drawings")
		(19 "Cmts.User" user "User.Comments")
		(21 "Eco1.User" user "User.Eco1")
		(23 "Eco2.User" user "User.Eco2")
		(25 "Edge.Cuts" user "Board Geometry/Outline")
		(27 "Margin" user)
		(31 "F.CrtYd" user "Package Geometry/Place Bound Top")
		(29 "B.CrtYd" user "Package Geometry/Place Bound Bottom")
		(35 "F.Fab" user "Ref Des/Assembly Top")
		(33 "B.Fab" user "Ref Des/Assembly Bottom")
	)
	(footprint ""
		(layer "F.Cu")
		(at 216.67724 -103.123492 180)
		(property "Reference" "R841"
			(at 0 0 180)
			(layer "F.SilkS")
			(hide yes)
			(effects
				(font
					(size 1.27 1.27)
				)
			)
		)
		(property "Value" "39K2R2F-L-GP"
			(at 0.064008 -3.993896 180)
			(unlocked yes)
			(layer "F.Fab")
			(hide yes)
			(effects
				(font
					(size 1.016 1.016)
					(thickness 0.1524)
				)
			)
		)
		(property "Device Type" "R402H16"
			(at 0.064008 -5.517896 180)
			(unlocked yes)
			(layer "F.Fab")
			(hide yes)
			(effects
				(font
					(size 1.016 1.016)
					(thickness 0.1524)
				)
			)
		)
		(duplicate_pad_numbers_are_jumpers no)
		(fp_line
			(start 0.508 -0.9398)
			(end -0.508 -0.9398)
			(stroke
				(width 0.1524)
				(type default)
			)
			(layer "F.SilkS")
		)
		(fp_line
			(start -0.508 -0.9398)
			(end -0.508 0.9398)
			(stroke
				(width 0.1524)
				(type default)
			)
			(layer "F.SilkS")
		)
		(fp_rect
			(start -0.508 0.9398)
			(end 0.508 -0.9398)
			(stroke
				(width 0)
				(type default)
			)
			(fill no)
			(layer "F.CrtYd")
		)
		(fp_rect
			(start -0.508 0.9398)
			(end 0.508 -0.9398)
			(stroke
				(width 0)
				(type default)
			)
			(fill no)
			(layer "F.Fab")
		)
		(pad "1" smd custom
			(at 0 -0.4445 180)
			(size 0.1397 0.1397)
			(layers "F.Cu" "F.Mask" "F.Paste")
			(net "P3V3_M2_MODE")
			(options
				(clearance outline)
				(anchor circle)
			)
			(primitives
				(gr_poly
					(pts
						(arc
							(start -0.1778 -0.2794)
							(mid -0.249642 -0.249642)
							(end -0.2794 -0.1778)
						)
						(arc
							(start -0.2794 0.1778)
							(mid -0.249642 0.249642)
							(end -0.1778 0.2794)
						)
						(arc
							(start 0.1778 0.2794)
							(mid 0.249642 0.249642)
							(end 0.2794 0.1778)
						)
						(arc
							(start 0.2794 -0.1778)
							(mid 0.249642 -0.249642)
							(end 0.1778 -0.2794)
						)
					)
					(width 0)
					(fill yes)
				)
			)
		)
		(pad "2" smd custom
			(at 0 0.4445 180)
			(size 0.1397 0.1397)
			(layers "F.Cu" "F.Mask" "F.Paste")
			(net "IOM_FULL_PGOOD")
			(options
				(clearance outline)
				(anchor circle)
			)
			(primitives
				(gr_poly
					(pts
						(arc
							(start -0.1778 -0.2794)
							(mid -0.249642 -0.249642)
							(end -0.2794 -0.1778)
						)
						(arc
							(start -0.2794 0.1778)
							(mid -0.249642 0.249642)
							(end -0.1778 0.2794)
						)
						(arc
							(start 0.1778 0.2794)
							(mid 0.249642 0.249642)
							(end 0.2794 0.1778)
						)
						(arc
							(start 0.2794 -0.1778)
							(mid 0.249642 -0.249642)
							(end 0.1778 -0.2794)
						)
					)
					(width 0)
					(fill yes)
				)
			)
		)
	)
	(footprint ""
		(layer "F.Cu")
		(at 77.372718 -150.261574)
		(property "Reference" "R408"
			(at 0 0 0)
			(layer "F.SilkS")
			(hide yes)
			(effects
				(font
					(size 1.27 1.27)
				)
			)
		)
		(property "Value" "4K7R2F-GP"
			(at 0.064008 -3.993896 0)
			(unlocked yes)
			(layer "F.Fab")
			(hide yes)
			(effects
				(font
					(size 1.016 1.016)
					(thickness 0.1524)
				)
			)
		)
		(property "Device Type" "R402H16"
			(at 0.064008 -5.517896 0)
			(unlocked yes)
			(layer "F.Fab")
			(hide yes)
			(effects
				(font
					(size 1.016 1.016)
					(thickness 0.1524)
				)
			)
		)
		(duplicate_pad_numbers_are_jumpers no)
		(fp_line
			(start -0.508 -0.9398)
			(end -0.508 0.9398)
			(stroke
				(width 0.1524)
				(type default)
			)
			(layer "F.SilkS")
		)
		(fp_line
			(start 0.508 -0.9398)
			(end -0.508 -0.9398)
			(stroke
				(width 0.1524)
				(type default)
			)
			(layer "F.SilkS")
		)
		(fp_rect
			(start -0.508 0.9398)
			(end 0.508 -0.9398)
			(stroke
				(width 0)
				(type default)
			)
			(fill no)
			(layer "F.CrtYd")
		)
		(fp_rect
			(start -0.508 0.9398)
			(end 0.508 -0.9398)
			(stroke
				(width 0)
				(type default)
			)
			(fill no)
			(layer "F.Fab")
		)
		(pad "1" smd custom
			(at 0 -0.4445)
			(size 0.1397 0.1397)
			(layers "F.Cu" "F.Mask" "F.Paste")
			(net "COMP_TO_BMC_RESET_R")
			(options
				(clearance outline)
				(anchor circle)
			)
			(primitives
				(gr_poly
					(pts
						(arc
							(start -0.1778 -0.2794)
							(mid -0.249642 -0.249642)
							(end -0.2794 -0.1778)
						)
						(arc
							(start -0.2794 0.1778)
							(mid -0.249642 0.249642)
							(end -0.1778 0.2794)
						)
						(arc
							(start 0.1778 0.2794)
							(mid 0.249642 0.249642)
							(end 0.2794 0.1778)
						)
						(arc
							(start 0.2794 -0.1778)
							(mid 0.249642 -0.249642)
							(end 0.1778 -0.2794)
						)
					)
					(width 0)
					(fill yes)
				)
			)
		)
		(pad "2" smd custom
			(at 0 0.4445)
			(size 0.1397 0.1397)
			(layers "F.Cu" "F.Mask" "F.Paste")
			(net "GND")
			(options
				(clearance outline)
				(anchor circle)
			)
			(primitives
				(gr_poly
					(pts
						(arc
							(start -0.1778 -0.2794)
							(mid -0.249642 -0.249642)
							(end -0.2794 -0.1778)
						)
						(arc
							(start -0.2794 0.1778)
							(mid -0.249642 0.249642)
							(end -0.1778 0.2794)
						)
						(arc
							(start 0.1778 0.2794)
							(mid 0.249642 0.249642)
							(end 0.2794 0.1778)
						)
						(arc
							(start 0.2794 -0.1778)
							(mid 0.249642 -0.249642)
							(end 0.1778 -0.2794)
						)
					)
					(width 0)
					(fill yes)
				)
			)
		)
	)
	(footprint ""
		(layer "F.Cu")
		(at 85.470746 -145.471134 -90)
		(property "Reference" "R130"
			(at 0 0 270)
			(layer "F.SilkS")
			(hide yes)
			(effects
				(font
					(size 1.27 1.27)
				)
			)
		)
		(property "Value" "0R2J-2-GP"
			(at 0.064008 -3.993896 270)
			(unlocked yes)
			(layer "F.Fab")
			(hide yes)
			(effects
				(font
					(size 1.016 1.016)
					(thickness 0.1524)
				)
			)
		)
		(property "Device Type" "R402H16"
			(at 0.064008 -5.517896 270)
			(unlocked yes)
			(layer "F.Fab")
			(hide yes)
			(effects
				(font
					(size 1.016 1.016)
					(thickness 0.1524)
				)
			)
		)
		(duplicate_pad_numbers_are_jumpers no)
		(fp_line
			(start -0.508 -0.9398)
			(end -0.508 0.9398)
			(stroke
				(width 0.1524)
				(type default)
			)
			(layer "F.SilkS")
		)
		(fp_line
			(start 0.508 -0.9398)
			(end -0.508 -0.9398)
			(stroke
				(width 0.1524)
				(type default)
			)
			(layer "F.SilkS")
		)
		(fp_rect
			(start -0.508 0.9398)
			(end 0.508 -0.9398)
			(stroke
				(width 0)
				(type default)
			)
			(fill no)
			(layer "F.CrtYd")
		)
		(fp_rect
			(start -0.508 0.9398)
			(end 0.508 -0.9398)
			(stroke
				(width 0)
				(type default)
			)
			(fill no)
			(layer "F.Fab")
		)
		(pad "1" smd custom
			(at 0 -0.4445 270)
			(size 0.1397 0.1397)
			(layers "F.Cu" "F.Mask" "F.Paste")
			(net "I2C_EXP_RMT_SDA")
			(options
				(clearance outline)
				(anchor circle)
			)
			(primitives
				(gr_poly
					(pts
						(arc
							(start -0.1778 -0.2794)
							(mid -0.249642 -0.249642)
							(end -0.2794 -0.1778)
						)
						(arc
							(start -0.2794 0.1778)
							(mid -0.249642 0.249642)
							(end -0.1778 0.2794)
						)
						(arc
							(start 0.1778 0.2794)
							(mid 0.249642 0.249642)
							(end 0.2794 0.1778)
						)
						(arc
							(start 0.2794 -0.1778)
							(mid 0.249642 -0.249642)
							(end 0.1778 -0.2794)
						)
					)
					(width 0)
					(fill yes)
				)
			)
		)
		(pad "2" smd custom
			(at 0 0.4445 270)
			(size 0.1397 0.1397)
			(layers "F.Cu" "F.Mask" "F.Paste")
			(net "I2C_EXP_RMT_SDA_R")
			(options
				(clearance outline)
				(anchor circle)
			)
			(primitives
				(gr_poly
					(pts
						(arc
							(start -0.1778 -0.2794)
							(mid -0.249642 -0.249642)
							(end -0.2794 -0.1778)
						)
						(arc
							(start -0.2794 0.1778)
							(mid -0.249642 0.249642)
							(end -0.1778 0.2794)
						)
						(arc
							(start 0.1778 0.2794)
							(mid 0.249642 0.249642)
							(end 0.2794 0.1778)
						)
						(arc
							(start 0.2794 -0.1778)
							(mid 0.249642 -0.249642)
							(end 0.1778 -0.2794)
						)
					)
					(width 0)
					(fill yes)
				)
			)
		)
	)
	(footprint ""
		(layer "F.Cu")
		(at 59.8678 -138.303)
		(property "Reference" "TP71"
			(at 0 0 0)
			(layer "F.SilkS")
			(hide yes)
			(effects
				(font
					(size 1.27 1.27)
				)
			)
		)
		(property "Value" "TPAD28-2-GP"
			(at -0.0127 -1.6637 0)
			(unlocked yes)
			(layer "F.Fab")
			(hide yes)
			(effects
				(font
					(size 1.016 1.016)
					(thickness 0.1524)
				)
			)
		)
		(property "Device Type" "TPAD28"
			(at -0.0127 -3.1877 0)
			(unlocked yes)
			(layer "F.Fab")
			(hide yes)
			(effects
				(font
					(size 1.016 1.016)
					(thickness 0.1524)
				)
			)
		)
		(duplicate_pad_numbers_are_jumpers no)
		(fp_poly
			(pts
				(arc
					(start 0.3556 0)
					(mid -0.3556 0)
					(end 0.3556 0)
				)
			)
			(stroke
				(width 0)
				(type default)
			)
			(fill no)
			(layer "F.CrtYd")
		)
		(fp_poly
			(pts
				(arc
					(start 0.6096 0)
					(mid -0.6096 0)
					(end 0.6096 0)
				)
			)
			(stroke
				(width 0)
				(type default)
			)
			(fill no)
			(layer "F.Fab")
		)
		(pad "1" smd circle
			(at 0 0)
			(size 0.7112 0.7112)
			(layers "F.Cu" "F.Mask" "F.Paste")
			(net "TP_BMC_GPIOI4")
		)
	)
	(footprint ""
		(layer "F.Cu")
		(at 94.98838 -21.9202 90)
		(property "Reference" "D17"
			(at 0 0 90)
			(layer "F.SilkS")
			(hide yes)
			(effects
				(font
					(size 1.27 1.27)
				)
			)
		)
		(property "Value" "PESD5V0S1BL-1-GP"
			(at 1.8923 -1.5621 90)
			(unlocked yes)
			(layer "F.Fab")
			(hide yes)
			(effects
				(font
					(size 1.016 1.016)
					(thickness 0.1524)
				)
			)
		)
		(property "Device Type" "SOD882-10D6-1H20"
			(at 1.8923 -3.0861 90)
			(unlocked yes)
			(layer "F.Fab")
			(hide yes)
			(effects
				(font
					(size 1.016 1.016)
					(thickness 0.1524)
				)
			)
		)
		(duplicate_pad_numbers_are_jumpers no)
		(fp_line
			(start -0.3048 -0.9271)
			(end 0.3048 -0.9271)
			(stroke
				(width 0.254)
				(type default)
			)
			(layer "F.SilkS")
		)
		(fp_rect
			(start -0.2921 0.4953)
			(end 0.2921 -0.4953)
			(stroke
				(width 0)
				(type default)
			)
			(fill no)
			(layer "F.CrtYd")
		)
		(fp_poly
			(pts
				(xy -0.4318 0.8001) (xy -0.4318 -0.266192) (xy -0.2921 -0.266192) (xy -0.2921 0.4953) (xy 0.2921 0.4953)
				(xy 0.2921 -0.4953) (xy -0.2921 -0.4953) (xy -0.2921 -0.2667) (xy -0.4318 -0.2667) (xy -0.4318 -0.8001)
				(xy 0.4318 -0.8001) (xy 0.4318 0.8001)
			)
			(stroke
				(width 0)
				(type default)
			)
			(fill no)
			(layer "F.CrtYd")
		)
		(fp_rect
			(start -0.4318 0.8001)
			(end 0.4318 -0.8001)
			(stroke
				(width 0)
				(type default)
			)
			(fill no)
			(layer "F.Fab")
		)
		(pad "1" smd custom
			(at 0 -0.4445 90)
			(size 0.1143 0.1143)
			(layers "F.Cu" "F.Mask" "F.Paste")
			(net "UART_IOM_RX")
			(options
				(clearance outline)
				(anchor circle)
			)
			(primitives
				(gr_poly
					(pts
						(arc
							(start -0.2032 0.2286)
							(mid -0.275042 0.198842)
							(end -0.3048 0.127)
						)
						(arc
							(start -0.3048 -0.127)
							(mid -0.275042 -0.198842)
							(end -0.2032 -0.2286)
						)
						(arc
							(start 0.2032 -0.2286)
							(mid 0.275042 -0.198842)
							(end 0.3048 -0.127)
						)
						(arc
							(start 0.3048 0.127)
							(mid 0.275042 0.198842)
							(end 0.2032 0.2286)
						)
					)
					(width 0)
					(fill yes)
				)
			)
		)
		(pad "2" smd custom
			(at 0 0.4445 90)
			(size 0.1143 0.1143)
			(layers "F.Cu" "F.Mask" "F.Paste")
			(net "GND")
			(options
				(clearance outline)
				(anchor circle)
			)
			(primitives
				(gr_poly
					(pts
						(arc
							(start 0.2032 -0.2286)
							(mid 0.275042 -0.198842)
							(end 0.3048 -0.127)
						)
						(arc
							(start 0.3048 0.127)
							(mid 0.275042 0.198842)
							(end 0.2032 0.2286)
						)
						(arc
							(start -0.2032 0.2286)
							(mid -0.275042 0.198842)
							(end -0.3048 0.127)
						)
						(arc
							(start -0.3048 -0.127)
							(mid -0.275042 -0.198842)
							(end -0.2032 -0.2286)
						)
					)
					(width 0)
					(fill yes)
				)
			)
		)
	)
	(footprint ""
		(layer "F.Cu")
		(at 93.72092 -61.292232 90)
		(property "Reference" "R719"
			(at 0 0 90)
			(layer "F.SilkS")
			(hide yes)
			(effects
				(font
					(size 1.27 1.27)
				)
			)
		)
		(property "Value" "100KR2J-4-GP"
			(at 0.064008 -3.993896 90)
			(unlocked yes)
			(layer "F.Fab")
			(hide yes)
			(effects
				(font
					(size 1.016 1.016)
					(thickness 0.1524)
				)
			)
		)
		(property "Device Type" "R402H15"
			(at 0.064008 -5.517896 90)
			(unlocked yes)
			(layer "F.Fab")
			(hide yes)
			(effects
				(font
					(size 1.016 1.016)
					(thickness 0.1524)
				)
			)
		)
		(duplicate_pad_numbers_are_jumpers no)
		(fp_line
			(start 0.508 -0.9398)
			(end -0.508 -0.9398)
			(stroke
				(width 0.1524)
				(type default)
			)
			(layer "F.SilkS")
		)
		(fp_line
			(start -0.508 -0.9398)
			(end -0.508 0.9398)
			(stroke
				(width 0.1524)
				(type default)
			)
			(layer "F.SilkS")
		)
		(fp_rect
			(start -0.508 0.9398)
			(end 0.508 -0.9398)
			(stroke
				(width 0)
				(type default)
			)
			(fill no)
			(layer "F.CrtYd")
		)
		(fp_rect
			(start -0.508 0.9398)
			(end 0.508 -0.9398)
			(stroke
				(width 0)
				(type default)
			)
			(fill no)
			(layer "F.Fab")
		)
		(pad "1" smd custom
			(at 0 -0.4445 90)
			(size 0.1397 0.1397)
			(layers "F.Cu" "F.Mask" "F.Paste")
			(net "GND")
			(options
				(clearance outline)
				(anchor circle)
			)
			(primitives
				(gr_poly
					(pts
						(arc
							(start -0.1778 -0.2794)
							(mid -0.249642 -0.249642)
							(end -0.2794 -0.1778)
						)
						(arc
							(start -0.2794 0.1778)
							(mid -0.249642 0.249642)
							(end -0.1778 0.2794)
						)
						(arc
							(start 0.1778 0.2794)
							(mid 0.249642 0.249642)
							(end 0.2794 0.1778)
						)
						(arc
							(start 0.2794 -0.1778)
							(mid 0.249642 -0.249642)
							(end 0.1778 -0.2794)
						)
					)
					(width 0)
					(fill yes)
				)
			)
		)
		(pad "2" smd custom
			(at 0 0.4445 90)
			(size 0.1397 0.1397)
			(layers "F.Cu" "F.Mask" "F.Paste")
			(net "IOM_FULL_PWR_EN")
			(options
				(clearance outline)
				(anchor circle)
			)
			(primitives
				(gr_poly
					(pts
						(arc
							(start -0.1778 -0.2794)
							(mid -0.249642 -0.249642)
							(end -0.2794 -0.1778)
						)
						(arc
							(start -0.2794 0.1778)
							(mid -0.249642 0.249642)
							(end -0.1778 0.2794)
						)
						(arc
							(start 0.1778 0.2794)
							(mid 0.249642 0.249642)
							(end 0.2794 0.1778)
						)
						(arc
							(start 0.2794 -0.1778)
							(mid 0.249642 -0.249642)
							(end 0.1778 -0.2794)
						)
					)
					(width 0)
					(fill yes)
				)
			)
		)
	)
	(footprint ""
		(layer "F.Cu")
		(at 99.373944 -148.61032 -90)
		(property "Reference" "R35"
			(at 0 0 270)
			(layer "F.SilkS")
			(hide yes)
			(effects
				(font
					(size 1.27 1.27)
				)
			)
		)
		(property "Value" "4K7R2F-GP"
			(at 0.064008 -3.993896 270)
			(unlocked yes)
			(layer "F.Fab")
			(hide yes)
			(effects
				(font
					(size 1.016 1.016)
					(thickness 0.1524)
				)
			)
		)
		(property "Device Type" "R402H16"
			(at 0.064008 -5.517896 270)
			(unlocked yes)
			(layer "F.Fab")
			(hide yes)
			(effects
				(font
					(size 1.016 1.016)
					(thickness 0.1524)
				)
			)
		)
		(duplicate_pad_numbers_are_jumpers no)
		(fp_line
			(start -0.508 -0.9398)
			(end -0.508 0.9398)
			(stroke
				(width 0.1524)
				(type default)
			)
			(layer "F.SilkS")
		)
		(fp_line
			(start 0.508 -0.9398)
			(end -0.508 -0.9398)
			(stroke
				(width 0.1524)
				(type default)
			)
			(layer "F.SilkS")
		)
		(fp_rect
			(start -0.508 0.9398)
			(end 0.508 -0.9398)
			(stroke
				(width 0)
				(type default)
			)
			(fill no)
			(layer "F.CrtYd")
		)
		(fp_rect
			(start -0.508 0.9398)
			(end 0.508 -0.9398)
			(stroke
				(width 0)
				(type default)
			)
			(fill no)
			(layer "F.Fab")
		)
		(pad "1" smd custom
			(at 0 -0.4445 270)
			(size 0.1397 0.1397)
			(layers "F.Cu" "F.Mask" "F.Paste")
			(net "P3V3_STBY")
			(options
				(clearance outline)
				(anchor circle)
			)
			(primitives
				(gr_poly
					(pts
						(arc
							(start -0.1778 -0.2794)
							(mid -0.249642 -0.249642)
							(end -0.2794 -0.1778)
						)
						(arc
							(start -0.2794 0.1778)
							(mid -0.249642 0.249642)
							(end -0.1778 0.2794)
						)
						(arc
							(start 0.1778 0.2794)
							(mid 0.249642 0.249642)
							(end 0.2794 0.1778)
						)
						(arc
							(start 0.2794 -0.1778)
							(mid 0.249642 -0.249642)
							(end 0.1778 -0.2794)
						)
					)
					(width 0)
					(fill yes)
				)
			)
		)
		(pad "2" smd custom
			(at 0 0.4445 270)
			(size 0.1397 0.1397)
			(layers "F.Cu" "F.Mask" "F.Paste")
			(net "USB_EN_3")
			(options
				(clearance outline)
				(anchor circle)
			)
			(primitives
				(gr_poly
					(pts
						(arc
							(start -0.1778 -0.2794)
							(mid -0.249642 -0.249642)
							(end -0.2794 -0.1778)
						)
						(arc
							(start -0.2794 0.1778)
							(mid -0.249642 0.249642)
							(end -0.1778 0.2794)
						)
						(arc
							(start 0.1778 0.2794)
							(mid 0.249642 0.249642)
							(end 0.2794 0.1778)
						)
						(arc
							(start 0.2794 -0.1778)
							(mid 0.249642 -0.249642)
							(end 0.1778 -0.2794)
						)
					)
					(width 0)
					(fill yes)
				)
			)
		)
	)
)
